#ISCELL
  mstr_symbols design_note *
  *
#ISCELL
  mstr_symbols intel_corp_bpage *
  *
#CELL
  mstr_discrete cap *
  page42_i10
#CELL
  dev_discrete cap_a *
  page42_i100
#ISCELL
  mstr_symbols gnd *
  page42_i101
#CELL
  dev_discrete cap_a *
  page42_i102
#CELL
  dev_discrete cap_a *
  page42_i103
#CELL
  dev_discrete cap_a *
  page42_i104
#ISCELL
  mstr_symbols gnd *
  page42_i105
#CELL
  dev_discrete cap_a *
  page42_i106
#CELL
  dev_discrete cap_a *
  page42_i107
#CELL
  mstr_discrete cap *
  page42_i108
#CELL
  dev_discrete cap_a *
  page42_i109
#ISCELL
  mstr_symbols gnd *
  page42_i110
#CELL
  dev_discrete cap_a *
  page42_i111
#CELL
  dev_discrete cap_a *
  page42_i112
#CELL
  dev_discrete cap_a *
  page42_i113
#CELL
  dev_discrete cap_a *
  page42_i114
#CELL
  dev_discrete cap_a *
  page42_i115
#ISCELL
  mstr_symbols pvccin_cpu0 *
  page42_i116
#CELL
  dev_discrete cap_a *
  page42_i117
#CELL
  dev_discrete cap_a *
  page42_i118
#ISCELL
  mstr_symbols pvccin_cpu0 *
  page42_i119
#CELL
  mstr_discrete cap *
  page42_i12
#CELL
  dev_discrete cap_a *
  page42_i120
#ISCELL
  mstr_symbols pvccin_cpu0 *
  page42_i121
#ISCELL
  mstr_symbols gnd *
  page42_i122
#CELL
  dev_discrete cap_a *
  page42_i123
#ISCELL
  mstr_symbols gnd *
  page42_i124
#CELL
  dev_discrete cap_a *
  page42_i125
#CELL
  dev_discrete cap_a *
  page42_i126
#CELL
  dev_discrete cap_a *
  page42_i127
#CELL
  dev_discrete cap_a *
  page42_i128
#CELL
  dev_discrete cap_a *
  page42_i129
#CELL
  mstr_discrete cap *
  page42_i13
#CELL
  dev_discrete cap_a *
  page42_i130
#CELL
  dev_discrete cap_a *
  page42_i131
#CELL
  dev_discrete cap_a *
  page42_i132
#ISCELL
  mstr_symbols gnd *
  page42_i133
#CELL
  dev_discrete cap_a *
  page42_i134
#CELL
  dev_discrete cap_a *
  page42_i135
#CELL
  dev_discrete cap_a *
  page42_i136
#ISCELL
  mstr_symbols pvccin_cpu0 *
  page42_i137
#CELL
  dev_discrete cap_a *
  page42_i138
#ISCELL
  mstr_symbols pvccin_cpu0 *
  page42_i139
#CELL
  mstr_discrete cap *
  page42_i14
#CELL
  dev_discrete cap_a *
  page42_i140
#ISCELL
  mstr_symbols pvccin_cpu0 *
  page42_i141
#CELL
  dev_discrete cap_a *
  page42_i142
#ISCELL
  mstr_symbols vcc_core *
  page42_i144
#CELL
  dev_discrete cap_a *
  page42_i145
#CELL
  dev_discrete cap_a *
  page42_i147
#CELL
  mstr_discrete cap *
  page42_i148
#CELL
  mstr_discrete cap *
  page42_i149
#CELL
  dev_discrete cap_a *
  page42_i151
#CELL
  dev_discrete cap_a *
  page42_i152
#CELL
  dev_discrete cap_a *
  page42_i153
#CELL
  dev_discrete cap_a *
  page42_i154
#CELL
  dev_discrete cap_a *
  page42_i155
#CELL
  dev_discrete cap_a *
  page42_i156
#ISCELL
  mstr_symbols vcc_core *
  page42_i159
#ISCELL
  mstr_symbols pvccio_cpu0 *
  page42_i16
#CELL
  mstr_discrete cap *
  page42_i162
#CELL
  mstr_discrete cap *
  page42_i163
#CELL
  dev_discrete cap_a *
  page42_i164
#CELL
  mstr_discrete cap *
  page42_i17
#CELL
  mstr_discrete cap *
  page42_i172
#CELL
  dev_discrete cap_a *
  page42_i173
#CELL
  dev_discrete cap_a *
  page42_i174
#CELL
  dev_discrete cap_a *
  page42_i175
#CELL
  dev_discrete cap_a *
  page42_i176
#CELL
  dev_discrete cap_a *
  page42_i178
#CELL
  dev_discrete cap_a *
  page42_i179
#CELL
  mstr_discrete cap *
  page42_i18
#CELL
  dev_discrete cap_a *
  page42_i180
#ISCELL
  mstr_symbols vcc_core *
  page42_i181
#ISCELL
  mstr_symbols gnd *
  page42_i182
#CELL
  mstr_discrete cap *
  page42_i183
#CELL
  mstr_discrete cap *
  page42_i184
#CELL
  mstr_discrete cap *
  page42_i185
#CELL
  mstr_discrete cap *
  page42_i186
#CELL
  mstr_discrete cap *
  page42_i187
#CELL
  mstr_discrete cap *
  page42_i188
#CELL
  mstr_discrete cap *
  page42_i189
#CELL
  mstr_discrete cap *
  page42_i19
#CELL
  mstr_discrete cap *
  page42_i190
#CELL
  mstr_discrete cap *
  page42_i2
#ISCELL
  mstr_symbols gnd *
  page42_i20
#ISCELL
  mstr_symbols gnd *
  page42_i21
#ISCELL
  mstr_symbols pvsa_cpu0 *
  page42_i24
#CELL
  mstr_discrete cap *
  page42_i25
#CELL
  mstr_discrete cap *
  page42_i27
#CELL
  mstr_discrete cap *
  page42_i28
#ISCELL
  mstr_symbols gnd *
  page42_i29
#CELL
  mstr_discrete cap *
  page42_i3
#ISCELL
  mstr_symbols gnd *
  page42_i32
#CELL
  mstr_discrete cap *
  page42_i33
#ISCELL
  mstr_symbols gnd *
  page42_i35
#CELL
  mstr_discrete cap *
  page42_i37
#CELL
  mstr_discrete cap *
  page42_i38
#ISCELL
  mstr_symbols pvccin_cpu0 *
  page42_i39
#CELL
  mstr_discrete cap *
  page42_i4
#CELL
  mstr_discrete cap *
  page42_i40
#CELL
  mstr_discrete cap *
  page42_i41
#CELL
  mstr_discrete cap *
  page42_i42
#ISCELL
  mstr_symbols pvccin_cpu0 *
  page42_i43
#CELL
  mstr_discrete cap *
  page42_i44
#ISCELL
  mstr_symbols pvccin_cpu0 *
  page42_i45
#ISCELL
  mstr_symbols gnd *
  page42_i46
#ISCELL
  mstr_symbols gnd *
  page42_i48
#ISCELL
  mstr_symbols gnd *
  page42_i5
#CELL
  mstr_discrete cap *
  page42_i50
#CELL
  mstr_discrete cap *
  page42_i51
#CELL
  mstr_discrete cap *
  page42_i53
#CELL
  mstr_discrete cap *
  page42_i54
#CELL
  mstr_discrete cap *
  page42_i55
#CELL
  mstr_discrete cap *
  page42_i56
#CELL
  mstr_discrete cap *
  page42_i57
#ISCELL
  mstr_symbols gnd *
  page42_i58
#CELL
  mstr_discrete cap *
  page42_i59
#CELL
  mstr_discrete cap *
  page42_i6
#CELL
  mstr_discrete cap *
  page42_i60
#CELL
  mstr_discrete cap *
  page42_i61
#ISCELL
  mstr_symbols pvccin_cpu0 *
  page42_i62
#CELL
  mstr_discrete cap *
  page42_i63
#ISCELL
  mstr_symbols pvccin_cpu0 *
  page42_i64
#CELL
  mstr_discrete cap *
  page42_i65
#ISCELL
  mstr_symbols pvccin_cpu0 *
  page42_i66
#CELL
  dev_discrete cap_a *
  page42_i68
#CELL
  dev_discrete cap_a *
  page42_i69
#CELL
  dev_discrete cap_a *
  page42_i70
#ISCELL
  mstr_symbols gnd *
  page42_i71
#CELL
  dev_discrete cap_a *
  page42_i72
#ISCELL
  mstr_symbols gnd *
  page42_i73
#CELL
  dev_discrete cap_a *
  page42_i74
#CELL
  dev_discrete cap_a *
  page42_i75
#CELL
  dev_discrete cap_a *
  page42_i77
#ISCELL
  mstr_symbols pvccio_cpu0 *
  page42_i79
#CELL
  mstr_discrete cap *
  page42_i8
#CELL
  dev_discrete cap_a *
  page42_i80
#CELL
  dev_discrete cap_a *
  page42_i81
#CELL
  dev_discrete cap_a *
  page42_i83
#CELL
  dev_discrete cap_a *
  page42_i88
#CELL
  dev_discrete cap_a *
  page42_i89
#CELL
  mstr_discrete cap *
  page42_i9
#CELL
  dev_discrete cap_a *
  page42_i90
#CELL
  mstr_discrete cap *
  page42_i91
#ISCELL
  mstr_symbols gnd *
  page42_i92
#CELL
  mstr_discrete cap *
  page42_i93
#CELL
  mstr_discrete cap *
  page42_i94
#CELL
  dev_discrete cap_a *
  page42_i98
#ISCELL
  mstr_symbols pvsa_cpu0 *
  page42_i99
